(kicad_pcb
	(version 20241229)
	(generator "pcbnew")
	(generator_version "9.0")
	(general
		(thickness 1.711)
		(legacy_teardrops no)
	)
	(paper "A4")
	(title_block
		(title "Antmicro Baseboard for Jetson AGX Thor")
		(date "2026-02-18")
		(rev "1.1.0")
		(company "Antmicro Ltd")
		(comment 1 "www.antmicro.com")
		(comment 9 "footprints 672-674 of 1170")
	)
	(layers
		(0 "F.Cu" signal)
		(4 "In1.Cu" signal)
		(6 "In2.Cu" signal)
		(8 "In3.Cu" signal)
		(10 "In4.Cu" jumper)
		(12 "In5.Cu" signal)
		(14 "In6.Cu" signal)
		(16 "In7.Cu" signal)
		(18 "In8.Cu" signal)
		(2 "B.Cu" signal)
		(9 "F.Adhes" user "F.Adhesive")
		(11 "B.Adhes" user "B.Adhesive")
		(13 "F.Paste" user)
		(15 "B.Paste" user)
		(5 "F.SilkS" user "F.Silkscreen")
		(7 "B.SilkS" user "B.Silkscreen")
		(1 "F.Mask" user)
		(3 "B.Mask" user)
		(17 "Dwgs.User" user "User.Drawings")
		(19 "Cmts.User" user "User.Comments")
		(21 "Eco1.User" user "User.Eco1")
		(23 "Eco2.User" user "User.Eco2")
		(25 "Edge.Cuts" user)
		(27 "Margin" user)
		(31 "F.CrtYd" user "F.Courtyard")
		(29 "B.CrtYd" user "B.Courtyard")
		(35 "F.Fab" user)
		(33 "B.Fab" user)
	)
	(footprint "antmicro-footprints:Tag-Connect_TC2050-IDC-NL_2x5_P1.27mm"
		(layer "B.Cu")
		(at 196.4 97)
		(property "Reference" "J4"
			(at 0.75 3.15 180)
			(layer "B.SilkS")
			(effects
				(font
					(size 0.7 0.7)
					(thickness 0.15)
				)
				(justify left bottom mirror)
			)
		)
		(property "Value" "Tag-Connect_TC2050-IDC-NL_2x5_P1.27mm"
			(at 0 -4.4 180)
			(layer "B.Fab")
			(effects
				(font
					(size 0.7 0.7)
					(thickness 0.15)
				)
				(justify left bottom mirror)
			)
		)
		(property "Datasheet" "https://www.tag-connect.com/wp-content/uploads/bsk-pdf-manager/TC2050-IDC-NL_Datasheet_8.pdf"
			(at 0 0 180)
			(layer "B.Fab")
			(hide yes)
			(effects
				(font
					(size 1.27 1.27)
					(thickness 0.15)
				)
				(justify mirror)
			)
		)
		(property "Description" "Tag Connect 2x5 1.27mm terminal"
			(at 0 0 180)
			(layer "B.Fab")
			(hide yes)
			(effects
				(font
					(size 1.27 1.27)
					(thickness 0.15)
				)
				(justify mirror)
			)
		)
		(property "MPN" "TC2050-IDC-NL"
			(at 0 0 180)
			(unlocked yes)
			(layer "B.Fab")
			(hide yes)
			(effects
				(font
					(size 1 1)
					(thickness 0.15)
				)
				(justify mirror)
			)
		)
		(property "Manufacturer" "Tag Connect"
			(at 0 0 180)
			(unlocked yes)
			(layer "B.Fab")
			(hide yes)
			(effects
				(font
					(size 1 1)
					(thickness 0.15)
				)
				(justify mirror)
			)
		)
		(property "Author" "Antmicro"
			(at 0 0 180)
			(unlocked yes)
			(layer "B.Fab")
			(hide yes)
			(effects
				(font
					(size 1 1)
					(thickness 0.15)
				)
				(justify mirror)
			)
		)
		(property "License" "Apache-2.0"
			(at 0 0 180)
			(unlocked yes)
			(layer "B.Fab")
			(hide yes)
			(effects
				(font
					(size 1 1)
					(thickness 0.15)
				)
				(justify mirror)
			)
		)
		(sheetname "/USB Debug, PD/")
		(sheetfile "usb_debug_pd.kicad_sch")
		(attr exclude_from_bom)
		(fp_line
			(start -5.08 -0.8)
			(end -5.08 0.900001)
			(stroke
				(width 0.15)
				(type solid)
			)
			(layer "B.SilkS")
		)
		(fp_line
			(start -5.08 0.900001)
			(end -2.2 2.05)
			(stroke
				(width 0.15)
				(type solid)
			)
			(layer "B.SilkS")
		)
		(fp_line
			(start -3.101001 -1.269)
			(end -3.101 -0.4)
			(stroke
				(width 0.15)
				(type solid)
			)
			(layer "B.SilkS")
		)
		(fp_line
			(start -2.3 -2.049)
			(end -5.08 -0.8)
			(stroke
				(width 0.15)
				(type solid)
			)
			(layer "B.SilkS")
		)
		(fp_line
			(start -2.2 2.05)
			(end 4.7 2.05)
			(stroke
				(width 0.15)
				(type solid)
			)
			(layer "B.SilkS")
		)
		(fp_line
			(start 4.7 -2.049)
			(end -2.3 -2.049)
			(stroke
				(width 0.15)
				(type solid)
			)
			(layer "B.SilkS")
		)
		(fp_line
			(start 4.7 -2.049)
			(end 5.1 -1.7)
			(stroke
				(width 0.15)
				(type solid)
			)
			(layer "B.SilkS")
		)
		(fp_line
			(start 4.7 2.05)
			(end 5.1 1.7)
			(stroke
				(width 0.15)
				(type solid)
			)
			(layer "B.SilkS")
		)
		(fp_line
			(start 5.1 1.7)
			(end 5.1 -1.7)
			(stroke
				(width 0.15)
				(type solid)
			)
			(layer "B.SilkS")
		)
		(fp_line
			(start -5.330001 1.1)
			(end -2.3 2.3)
			(stroke
				(width 0.05)
				(type solid)
			)
			(layer "B.CrtYd")
		)
		(fp_line
			(start -5.33 -1)
			(end -5.330001 1.1)
			(stroke
				(width 0.05)
				(type solid)
			)
			(layer "B.CrtYd")
		)
		(fp_line
			(start -2.4 -2.29)
			(end -5.33 -1)
			(stroke
				(width 0.05)
				(type solid)
			)
			(layer "B.CrtYd")
		)
		(fp_line
			(start -2.3 2.3)
			(end 4.8 2.3)
			(stroke
				(width 0.05)
				(type solid)
			)
			(layer "B.CrtYd")
		)
		(fp_line
			(start 4.8 -2.29)
			(end -2.4 -2.29)
			(stroke
				(width 0.05)
				(type solid)
			)
			(layer "B.CrtYd")
		)
		(fp_line
			(start 4.8 -2.29)
			(end 5.32 -1.8)
			(stroke
				(width 0.05)
				(type solid)
			)
			(layer "B.CrtYd")
		)
		(fp_line
			(start 4.8 2.3)
			(end 5.32 1.8)
			(stroke
				(width 0.05)
				(type solid)
			)
			(layer "B.CrtYd")
		)
		(fp_line
			(start 5.32 1.8)
			(end 5.32 -1.8)
			(stroke
				(width 0.05)
				(type solid)
			)
			(layer "B.CrtYd")
		)
		(fp_text user "Author: Antmicro"
			(at -6.223 -7.249001 180)
			(layer "B.Fab")
			(effects
				(font
					(size 0.7 0.7)
					(thickness 0.15)
				)
				(justify left bottom mirror)
			)
		)
		(fp_text user "${REFERENCE}"
			(at -6.223 -6.048999 180)
			(layer "B.Fab")
			(effects
				(font
					(size 0.7 0.7)
					(thickness 0.15)
				)
				(justify left bottom mirror)
			)
		)
		(fp_text user "License: Apache-2.0"
			(at -6.223 -8.449 180)
			(layer "B.Fab")
			(effects
				(font
					(size 0.7 0.7)
					(thickness 0.15)
				)
				(justify left bottom mirror)
			)
		)
		(pad "" np_thru_hole circle
			(at -3.81 0)
			(size 0.9906 0.9906)
			(drill 0.9906)
			(layers "*.Cu" "*.Mask")
		)
		(pad "" np_thru_hole circle
			(at 3.809 -1.015)
			(size 0.9906 0.9906)
			(drill 0.9906)
			(layers "*.Cu" "*.Mask")
		)
		(pad "" np_thru_hole circle
			(at 3.809 1.016)
			(size 0.9906 0.9906)
			(drill 0.9906)
			(layers "*.Cu" "*.Mask")
		)
		(pad "1" connect circle
			(at -2.54 -0.634)
			(size 0.7874 0.7874)
			(layers "B.Cu" "B.Mask")
			(net 271 "FLASH_PWR")
			(pinfunction "1")
			(pintype "passive")
		)
		(pad "2" connect circle
			(at -1.27 -0.634)
			(size 0.7874 0.7874)
			(layers "B.Cu" "B.Mask")
			(net 812 "/USB Debug, PD/~{CS}")
			(pinfunction "2")
			(pintype "passive")
		)
		(pad "3" connect circle
			(at 0 -0.634)
			(size 0.7874 0.7874)
			(layers "B.Cu" "B.Mask")
			(net 1 "GND")
			(pinfunction "3")
			(pintype "passive")
		)
		(pad "4" connect circle
			(at 1.269 -0.634)
			(size 0.7874 0.7874)
			(layers "B.Cu" "B.Mask")
			(net 532 "/USB Debug, PD/SCK")
			(pinfunction "4")
			(pintype "passive")
		)
		(pad "5" connect circle
			(at 2.539 -0.634)
			(size 0.7874 0.7874)
			(layers "B.Cu" "B.Mask")
			(net 1 "GND")
			(pinfunction "5")
			(pintype "passive")
		)
		(pad "6" connect circle
			(at 2.539 0.635)
			(size 0.7874 0.7874)
			(layers "B.Cu" "B.Mask")
			(net 810 "/USB Debug, PD/MISO")
			(pinfunction "6")
			(pintype "passive")
		)
		(pad "7" connect circle
			(at 1.269 0.635)
			(size 0.7874 0.7874)
			(layers "B.Cu" "B.Mask")
			(net 809 "unconnected-(J4-Pad7)")
			(pinfunction "7")
			(pintype "passive+no_connect")
		)
		(pad "8" connect circle
			(at 0 0.635)
			(size 0.7874 0.7874)
			(layers "B.Cu" "B.Mask")
			(net 811 "/USB Debug, PD/MOSI")
			(pinfunction "8")
			(pintype "passive")
		)
		(pad "9" connect circle
			(at -1.27 0.635)
			(size 0.7874 0.7874)
			(layers "B.Cu" "B.Mask")
			(net 1 "GND")
			(pinfunction "9")
			(pintype "passive")
		)
		(pad "10" connect circle
			(at -2.54 0.635)
			(size 0.7874 0.7874)
			(layers "B.Cu" "B.Mask")
			(net 808 "unconnected-(J4-Pad10)")
			(pinfunction "10")
			(pintype "passive+no_connect")
		)
	)
	(footprint "antmicro-footprints:R_0402_1005Metric"
		(layer "B.Cu")
		(at 166.25 57.5 -90)
		(descr "Resistor SMD 0402")
		(tags "resistor SMD 0402")
		(property "Reference" "R79"
			(at -3.58 -0.365532 90)
			(layer "B.SilkS")
			(effects
				(font
					(size 0.7 0.7)
					(thickness 0.15)
				)
				(justify left bottom mirror)
			)
		)
		(property "Value" "R_200R_0402"
			(at -1.011843 -1.772047 90)
			(layer "B.Fab")
			(effects
				(font
					(size 0.7 0.7)
					(thickness 0.15)
				)
				(justify left bottom mirror)
			)
		)
		(property "Datasheet" "https://www.bourns.com/docs/product-datasheets/cr.pdf"
			(at 0 0 90)
			(layer "B.Fab")
			(hide yes)
			(effects
				(font
					(size 1.27 1.27)
					(thickness 0.15)
				)
				(justify mirror)
			)
		)
		(property "Description" "SMD Chip Resistor, 200 ohm, ± 1%, 62.5 mW, 0402 [1005 Metric], Thick Film, General Purpose"
			(at 0 0 90)
			(layer "B.Fab")
			(hide yes)
			(effects
				(font
					(size 1.27 1.27)
					(thickness 0.15)
				)
				(justify mirror)
			)
		)
		(property "MPN" "CR0402-FX-2000GLF"
			(at 0 0 90)
			(unlocked yes)
			(layer "B.Fab")
			(hide yes)
			(effects
				(font
					(size 1 1)
					(thickness 0.15)
				)
				(justify mirror)
			)
		)
		(property "Manufacturer" "Bourns"
			(at 0 0 90)
			(unlocked yes)
			(layer "B.Fab")
			(hide yes)
			(effects
				(font
					(size 1 1)
					(thickness 0.15)
				)
				(justify mirror)
			)
		)
		(property "License" "Apache-2.0"
			(at 0 0 90)
			(unlocked yes)
			(layer "B.Fab")
			(hide yes)
			(effects
				(font
					(size 1 1)
					(thickness 0.15)
				)
				(justify mirror)
			)
		)
		(property "Author" "Antmicro"
			(at 0 0 90)
			(unlocked yes)
			(layer "B.Fab")
			(hide yes)
			(effects
				(font
					(size 1 1)
					(thickness 0.15)
				)
				(justify mirror)
			)
		)
		(property "Val" "200R"
			(at 0 0 90)
			(unlocked yes)
			(layer "B.Fab")
			(hide yes)
			(effects
				(font
					(size 1 1)
					(thickness 0.15)
				)
				(justify mirror)
			)
		)
		(property "Tolerance" "1%"
			(at 0 0 90)
			(unlocked yes)
			(layer "B.Fab")
			(hide yes)
			(effects
				(font
					(size 1 1)
					(thickness 0.15)
				)
				(justify mirror)
			)
		)
		(sheetname "/Power/")
		(sheetfile "power.kicad_sch")
		(attr smd)
		(fp_rect
			(start -0.925 0.47)
			(end 0.925 -0.47)
			(stroke
				(width 0.05)
				(type default)
			)
			(fill no)
			(layer "B.CrtYd")
		)
		(fp_rect
			(start -0.5 0.25)
			(end 0.5 -0.25)
			(stroke
				(width 0.15)
				(type solid)
			)
			(fill no)
			(layer "B.Fab")
		)
		(fp_text user "License: Apache-2.0"
			(at -0.95 -5.169 90)
			(layer "B.Fab")
			(effects
				(font
					(size 0.7 0.7)
					(thickness 0.15)
				)
				(justify left bottom mirror)
			)
		)
		(fp_text user "${REFERENCE}"
			(at -0.95 -3.168 90)
			(layer "B.Fab")
			(effects
				(font
					(size 0.7 0.7)
					(thickness 0.15)
				)
				(justify left bottom mirror)
			)
		)
		(fp_text user "Author: Antmicro"
			(at -0.95 -4.169 90)
			(layer "B.Fab")
			(effects
				(font
					(size 0.7 0.7)
					(thickness 0.15)
				)
				(justify left bottom mirror)
			)
		)
		(pad "1" smd roundrect
			(at -0.48 0 270)
			(size 0.59 0.64)
			(layers "B.Cu" "B.Mask" "B.Paste")
			(roundrect_rratio 0.25)
			(net 639 "Net-(D31-A)")
			(pintype "passive")
		)
		(pad "2" smd roundrect
			(at 0.48 0 270)
			(size 0.59 0.64)
			(layers "B.Cu" "B.Mask" "B.Paste")
			(roundrect_rratio 0.25)
			(net 2 "+3V3")
			(pintype "passive")
		)
	)
	(footprint "antmicro-footprints:LED_0603_1608Metric_G"
		(layer "B.Cu")
		(at 110.015 140.76 90)
		(descr "LED SMD 0603 Green")
		(tags "LED SMD 0603 Green")
		(property "Reference" "D33"
			(at -1.14 0.845 90)
			(layer "B.SilkS")
			(effects
				(font
					(size 0.7 0.7)
					(thickness 0.15)
				)
				(justify right top mirror)
			)
		)
		(property "Value" "LED_G_0603_LTST-C190GKT"
			(at -0.001 -1.599 90)
			(layer "B.Fab")
			(effects
				(font
					(size 0.7 0.7)
					(thickness 0.15)
				)
				(justify right top mirror)
			)
		)
		(property "Datasheet" "https://media.digikey.com/pdf/Data%20Sheets/Lite-On%20PDFs/LTST-C190GKT.pdf"
			(at 0 0 90)
			(layer "B.Fab")
			(hide yes)
			(effects
				(font
					(size 1.27 1.27)
					(thickness 0.15)
				)
				(justify mirror)
			)
		)
		(property "Description" "LED, Green, SMD, 0603, 20 mA, 2.1 V, 569 nm"
			(at 0 0 90)
			(layer "B.Fab")
			(hide yes)
			(effects
				(font
					(size 1.27 1.27)
					(thickness 0.15)
				)
				(justify mirror)
			)
		)
		(property "MPN" "LTST-C190GKT"
			(at 0 0 270)
			(unlocked yes)
			(layer "B.Fab")
			(hide yes)
			(effects
				(font
					(size 1 1)
					(thickness 0.15)
				)
				(justify mirror)
			)
		)
		(property "Manufacturer" "Lite-On"
			(at 0 0 270)
			(unlocked yes)
			(layer "B.Fab")
			(hide yes)
			(effects
				(font
					(size 1 1)
					(thickness 0.15)
				)
				(justify mirror)
			)
		)
		(property "Author" "Antmicro"
			(at 0 0 270)
			(unlocked yes)
			(layer "B.Fab")
			(hide yes)
			(effects
				(font
					(size 1 1)
					(thickness 0.15)
				)
				(justify mirror)
			)
		)
		(property "License" "Apache-2.0"
			(at 0 0 270)
			(unlocked yes)
			(layer "B.Fab")
			(hide yes)
			(effects
				(font
					(size 1 1)
					(thickness 0.15)
				)
				(justify mirror)
			)
		)
		(property "Public" "False"
			(at 0 0 270)
			(unlocked yes)
			(layer "B.Fab")
			(hide yes)
			(effects
				(font
					(size 1 1)
					(thickness 0.15)
				)
				(justify mirror)
			)
		)
		(property "Color" "Green"
			(at 0 0 270)
			(unlocked yes)
			(layer "B.Fab")
			(hide yes)
			(effects
				(font
					(size 1 1)
					(thickness 0.15)
				)
				(justify mirror)
			)
		)
		(sheetname "/M.2/")
		(sheetfile "m2.kicad_sch")
		(attr smd)
		(fp_line
			(start 0.22 -0.35)
			(end -0.22 -0.35)
			(stroke
				(width 0.15)
				(type solid)
			)
			(layer "B.SilkS")
		)
		(fp_line
			(start 0.105328 -0.201008)
			(end -0.094672 -0.001008)
			(stroke
				(width 0.1)
				(type solid)
			)
			(layer "B.SilkS")
		)
		(fp_line
			(start 0.105328 -0.201008)
			(end 0.105328 0.198992)
			(stroke
				(width 0.1)
				(type solid)
			)
			(layer "B.SilkS")
		)
		(fp_line
			(start -0.094672 -0.201008)
			(end -0.094672 0.198992)
			(stroke
				(width 0.1)
				(type solid)
			)
			(layer "B.SilkS")
		)
		(fp_line
			(start 0.105328 -0.001008)
			(end 0.24 -0.001)
			(stroke
				(width 0.1)
				(type solid)
			)
			(layer "B.SilkS")
		)
		(fp_line
			(start -0.094672 -0.001008)
			(end -0.24 -0.001008)
			(stroke
				(width 0.1)
				(type solid)
			)
			(layer "B.SilkS")
		)
		(fp_line
			(start -0.094672 -0.001008)
			(end 0.105328 0.198992)
			(stroke
				(width 0.1)
				(type solid)
			)
			(layer "B.SilkS")
		)
		(fp_line
			(start -1.18 0.319)
			(end -1.18 -0.321)
			(stroke
				(width 0.15)
				(type solid)
			)
			(layer "B.SilkS")
		)
		(fp_line
			(start 0.22 0.35)
			(end -0.22 0.35)
			(stroke
				(width 0.15)
				(type solid)
			)
			(layer "B.SilkS")
		)
		(fp_rect
			(start 1.25 -0.65)
			(end -1.25 0.65)
			(stroke
				(width 0.05)
				(type solid)
			)
			(fill no)
			(layer "B.CrtYd")
		)
		(fp_line
			(start 0.201 -0.2)
			(end 0.201 0)
			(stroke
				(width 0.15)
				(type solid)
			)
			(layer "B.Fab")
		)
		(fp_line
			(start -0.199 -0.2)
			(end -0.199 -0.1)
			(stroke
				(width 0.15)
				(type solid)
			)
			(layer "B.Fab")
		)
		(fp_line
			(start 0.599 0)
			(end 0.201 0)
			(stroke
				(width 0.15)
				(type solid)
			)
			(layer "B.Fab")
		)
		(fp_line
			(start 0.201 0)
			(end 0.201 0.202)
			(stroke
				(width 0.15)
				(type solid)
			)
			(layer "B.Fab")
		)
		(fp_line
			(start -0.101 0)
			(end 0.201 -0.2)
			(stroke
				(width 0.15)
				(type solid)
			)
			(layer "B.Fab")
		)
		(fp_line
			(start -0.199 0)
			(end -0.597 0)
			(stroke
				(width 0.15)
				(type solid)
			)
			(layer "B.Fab")
		)
		(fp_line
			(start 0.201 0.202)
			(end -0.101 0)
			(stroke
				(width 0.15)
				(type solid)
			)
			(layer "B.Fab")
		)
		(fp_line
			(start -0.199 0.202)
			(end -0.199 -0.1)
			(stroke
				(width 0.15)
				(type solid)
			)
			(layer "B.Fab")
		)
		(fp_rect
			(start 0.848 -0.4)
			(end -0.85 0.402)
			(stroke
				(width 0.15)
				(type solid)
			)
			(fill no)
			(layer "B.Fab")
		)
		(fp_text user "License: Apache-2.0"
			(at -1.4224 -3.599 90)
			(layer "B.Fab")
			(effects
				(font
					(size 0.7 0.7)
					(thickness 0.15)
				)
				(justify right top mirror)
			)
		)
		(fp_text user "${REFERENCE}"
			(at -1.4224 -5.999 90)
			(layer "B.Fab")
			(effects
				(font
					(size 0.7 0.7)
					(thickness 0.15)
				)
				(justify right top mirror)
			)
		)
		(fp_text user "Author: Antmicro"
			(at -1.4224 -4.799 90)
			(layer "B.Fab")
			(effects
				(font
					(size 0.7 0.7)
					(thickness 0.15)
				)
				(justify right top mirror)
			)
		)
		(pad "1" smd roundrect
			(at -0.7 0 270)
			(size 0.8 1)
			(layers "B.Cu" "B.Mask" "B.Paste")
			(roundrect_rratio 0.2)
			(net 34 "/M.2/~{LED_1}")
			(pinfunction "C")
			(pintype "passive")
		)
		(pad "2" smd roundrect
			(at 0.7 0 270)
			(size 0.8 1)
			(layers "B.Cu" "B.Mask" "B.Paste")
			(roundrect_rratio 0.2)
			(net 545 "Net-(D33-A)")
			(pinfunction "A")
			(pintype "passive")
		)
	)
)
